# S9S_MB_2U (Grand Teton) — schematic netlist excerpt (pin names and nets, part order shuffled) for the footprints in the layout excerpt that follows; sources: Cadence DE-HDL packaged netlist, KiCad conversion of 03242023_DA0F0TMBIJ0_F0T_Motherboard_J_brd_V01_OCP.brd

J86  PICOPROBE_BXA  DELTA-L 4.0 EMPTY  pkg TRIANG_LAUNCH_3PXB  page 308
  \1_p\  = DELTA_L_85_10INCH_IN4_DN
  \2_n\  = DELTA_L_85_10INCH_IN4_DP
  \3_g\  = DELTA_L_GND_1

(kicad_pcb
	(version 20260206)
	(generator "pcbnew")
	(generator_version "10.0")
	(general
		(thickness 1.6)
		(legacy_teardrops no)
	)
	(paper "A4")
	(title_block
		(title "03242023_DA0F0TMBIJ0_F0T_Motherboard_J_brd_V01_OCP.brd")
		(comment 1 "Grand Teton / footprints 5409-5409 of 6105")
	)
	(layers
		(0 "F.Cu" signal "TOP")
		(4 "In1.Cu" signal "GND")
		(6 "In2.Cu" signal "IN1")
		(8 "In3.Cu" signal "GND1")
		(10 "In4.Cu" signal "IN2")
		(12 "In5.Cu" signal "GND2")
		(14 "In6.Cu" signal "IN3")
		(16 "In7.Cu" signal "GND3")
		(18 "In8.Cu" signal "VCC")
		(20 "In9.Cu" signal "VCC1")
		(22 "In10.Cu" signal "GND4")
		(24 "In11.Cu" signal "IN4")
		(26 "In12.Cu" signal "GND5")
		(28 "In13.Cu" signal "IN5")
		(30 "In14.Cu" signal "GND6")
		(32 "In15.Cu" signal "IN6")
		(34 "In16.Cu" signal "GND7")
		(2 "B.Cu" signal "BOTTOM")
		(9 "F.Adhes" user "F.Adhesive")
		(11 "B.Adhes" user "B.Adhesive")
		(13 "F.Paste" user "Package Geometry/Pastemask Top")
		(15 "B.Paste" user "Package Geometry/Pastemask Bottom")
		(5 "F.SilkS" user "Ref Des/Silkscreen Top")
		(7 "B.SilkS" user "Ref Des/Silkscreen Bottom")
		(1 "F.Mask" user "Board Geometry/Soldermask Top")
		(3 "B.Mask" user "Board Geometry/Soldermask Bottom")
		(17 "Dwgs.User" user "User.Drawings")
		(19 "Cmts.User" user "User.Comments")
		(21 "Eco1.User" user "User.Eco1")
		(23 "Eco2.User" user "User.Eco2")
		(25 "Edge.Cuts" user "Board Geometry/Outline")
		(27 "Margin" user)
		(31 "F.CrtYd" user "Package Geometry/Place Bound Top")
		(29 "B.CrtYd" user "Package Geometry/Place Bound Bottom")
		(35 "F.Fab" user "Ref Des/Assembly Top")
		(33 "B.Fab" user "Ref Des/Assembly Bottom")
	)
	(footprint ""
		(layer "B.Cu")
		(at 250.65482 5.461)
		(property "Reference" "J86"
			(at 4.20751 1.143 270)
			(unlocked yes)
			(layer "B.SilkS")
			(effects
				(font
					(size 0.7874 0.5842)
					(thickness 0.1524)
				)
				(justify left mirror)
			)
		)
		(property "Value" ""
			(at 0 0 0)
			(layer "B.Fab")
			(effects
				(font
					(size 1.27 1.27)
				)
				(justify mirror)
			)
		)
		(duplicate_pad_numbers_are_jumpers no)
		(fp_line
			(start -1.2192 -2.1082)
			(end -1.2192 2.1082)
			(stroke
				(width 0.1524)
				(type default)
			)
			(layer "B.SilkS")
		)
		(fp_line
			(start -1.2192 2.1082)
			(end 1.2192 2.1082)
			(stroke
				(width 0.1524)
				(type default)
			)
			(layer "B.SilkS")
		)
		(fp_line
			(start 1.2192 -2.1082)
			(end -1.2192 -2.1082)
			(stroke
				(width 0.1524)
				(type default)
			)
			(layer "B.SilkS")
		)
		(fp_line
			(start 1.2192 2.1082)
			(end 1.2192 -2.1082)
			(stroke
				(width 0.1524)
				(type default)
			)
			(layer "B.SilkS")
		)
		(pad "" np_thru_hole circle
			(at -3.4671 -1.27 270)
			(size 1.0414 1.0414)
			(drill 1.0414)
			(layers "*.Cu" "*.Mask")
			(clearance 0.381)
			(thermal_gap 0.381)
		)
		(pad "" np_thru_hole circle
			(at -3.4671 1.27 270)
			(size 1.0414 1.0414)
			(drill 1.0414)
			(layers "*.Cu" "*.Mask")
			(clearance 0.381)
			(thermal_gap 0.381)
		)
		(pad "" np_thru_hole circle
			(at 2.8829 -1.27 270)
			(size 1.0414 1.0414)
			(drill 1.0414)
			(layers "*.Cu" "*.Mask")
			(clearance 0.381)
			(thermal_gap 0.381)
		)
		(pad "" np_thru_hole circle
			(at 2.8829 1.27 270)
			(size 1.0414 1.0414)
			(drill 1.0414)
			(layers "*.Cu" "*.Mask")
			(clearance 0.381)
			(thermal_gap 0.381)
		)
		(pad "1" smd rect
			(at -0.8255 -0.249936 270)
			(size 0.3048 0.508)
			(layers "B.Cu" "B.Mask" "B.Paste")
			(net "DELTA_L_85_10INCH_IN4_DN")
		)
		(pad "2" smd rect
			(at -0.8255 0.249936 270)
			(size 0.3048 0.508)
			(layers "B.Cu" "B.Mask" "B.Paste")
			(net "DELTA_L_85_10INCH_IN4_DP")
		)
		(pad "3" smd circle
			(at 0 0 180)
			(size 0 0)
			(layers "B.Cu" "B.Mask" "B.Paste")
			(net "DELTA_L_GND_1")
		)
		(zone
			(layers "F.Cu" "B.Cu" "In1.Cu" "In2.Cu" "In3.Cu" "In4.Cu" "In5.Cu" "In6.Cu"
				"In7.Cu" "In8.Cu" "In9.Cu" "In10.Cu" "In11.Cu" "In12.Cu" "In13.Cu" "In14.Cu"
				"In15.Cu" "In16.Cu"
			)
			(hatch none 0.5)
			(connect_pads
				(clearance 0)
			)
			(min_thickness 0.25)
			(keepout
				(tracks not_allowed)
				(vias allowed)
				(pads allowed)
				(copperpour not_allowed)
				(footprints allowed)
			)
			(placement
				(enabled no)
				(sheetname "")
			)
			(fill
				(thermal_gap 0.5)
				(thermal_bridge_width 0.5)
				(island_removal_mode 0)
			)
			(polygon
				(pts
					(arc
						(start 248.11482 4.191)
						(mid 246.26062 4.191)
						(end 248.11482 4.191)
					)
				)
			)
		)
		(zone
			(layers "F.Cu" "B.Cu" "In1.Cu" "In2.Cu" "In3.Cu" "In4.Cu" "In5.Cu" "In6.Cu"
				"In7.Cu" "In8.Cu" "In9.Cu" "In10.Cu" "In11.Cu" "In12.Cu" "In13.Cu" "In14.Cu"
				"In15.Cu" "In16.Cu"
			)
			(hatch none 0.5)
			(connect_pads
				(clearance 0)
			)
			(min_thickness 0.25)
			(keepout
				(tracks not_allowed)
				(vias allowed)
				(pads allowed)
				(copperpour not_allowed)
				(footprints allowed)
			)
			(placement
				(enabled no)
				(sheetname "")
			)
			(fill
				(thermal_gap 0.5)
				(thermal_bridge_width 0.5)
				(island_removal_mode 0)
			)
			(polygon
				(pts
					(arc
						(start 248.11482 6.731)
						(mid 246.26062 6.731)
						(end 248.11482 6.731)
					)
				)
			)
		)
		(zone
			(layers "F.Cu" "B.Cu" "In1.Cu" "In2.Cu" "In3.Cu" "In4.Cu" "In5.Cu" "In6.Cu"
				"In7.Cu" "In8.Cu" "In9.Cu" "In10.Cu" "In11.Cu" "In12.Cu" "In13.Cu" "In14.Cu"
				"In15.Cu" "In16.Cu"
			)
			(hatch none 0.5)
			(connect_pads
				(clearance 0)
			)
			(min_thickness 0.25)
			(keepout
				(tracks not_allowed)
				(vias allowed)
				(pads allowed)
				(copperpour not_allowed)
				(footprints allowed)
			)
			(placement
				(enabled no)
				(sheetname "")
			)
			(fill
				(thermal_gap 0.5)
				(thermal_bridge_width 0.5)
				(island_removal_mode 0)
			)
			(polygon
				(pts
					(arc
						(start 254.46482 4.191)
						(mid 252.61062 4.191)
						(end 254.46482 4.191)
					)
				)
			)
		)
		(zone
			(layers "F.Cu" "B.Cu" "In1.Cu" "In2.Cu" "In3.Cu" "In4.Cu" "In5.Cu" "In6.Cu"
				"In7.Cu" "In8.Cu" "In9.Cu" "In10.Cu" "In11.Cu" "In12.Cu" "In13.Cu" "In14.Cu"
				"In15.Cu" "In16.Cu"
			)
			(hatch none 0.5)
			(connect_pads
				(clearance 0)
			)
			(min_thickness 0.25)
			(keepout
				(tracks not_allowed)
				(vias allowed)
				(pads allowed)
				(copperpour not_allowed)
				(footprints allowed)
			)
			(placement
				(enabled no)
				(sheetname "")
			)
			(fill
				(thermal_gap 0.5)
				(thermal_bridge_width 0.5)
				(island_removal_mode 0)
			)
			(polygon
				(pts
					(arc
						(start 254.46482 6.731)
						(mid 252.61062 6.731)
						(end 254.46482 6.731)
					)
				)
			)
		)
		(zone
			(layer "B.Cu")
			(hatch none 0.5)
			(connect_pads
				(clearance 0)
			)
			(min_thickness 0.25)
			(keepout
				(tracks not_allowed)
				(vias allowed)
				(pads allowed)
				(copperpour not_allowed)
				(footprints allowed)
			)
			(placement
				(enabled no)
				(sheetname "")
			)
			(fill
				(thermal_gap 0.5)
				(thermal_bridge_width 0.5)
				(island_removal_mode 0)
			)
			(polygon
				(pts
					(xy 249.53722 4.91236) (xy 249.53722 5.007864) (xy 250.13412 5.007864) (xy 250.13412 5.414264)
					(xy 249.53722 5.414264) (xy 249.53722 5.507736) (xy 250.13412 5.507736) (xy 250.13412 5.914136)
					(xy 249.53722 5.914136) (xy 249.53722 6.00964) (xy 250.23572 6.00964) (xy 250.23572 4.91236)
				)
			)
		)
	)
)
